(kicad_pcb
	(version 20260206)
	(generator "pcbnew")
	(generator_version "10.0")
	(general
		(thickness 1.6)
		(legacy_teardrops no)
	)
	(paper "A4")
	(title_block
		(title "Bryce Canyon_F.DPB_16315-1-OCP.brd")
		(comment 1 "Bryce Canyon / footprints 1941-1945 of 2223")
	)
	(layers
		(0 "F.Cu" signal "TOP")
		(4 "In1.Cu" signal "L2GND")
		(6 "In2.Cu" signal "L3")
		(8 "In3.Cu" signal "L4GND")
		(10 "In4.Cu" signal "L5")
		(12 "In5.Cu" signal "L6VCC")
		(14 "In6.Cu" signal "L7VCC")
		(16 "In7.Cu" signal "L8")
		(18 "In8.Cu" signal "L9GND")
		(20 "In9.Cu" signal "L10")
		(22 "In10.Cu" signal "L11GND")
		(2 "B.Cu" signal "BOTTOM")
		(9 "F.Adhes" user "F.Adhesive")
		(11 "B.Adhes" user "B.Adhesive")
		(13 "F.Paste" user "Package Geometry/Pastemask Top")
		(15 "B.Paste" user "Package Geometry/Pastemask Bottom")
		(5 "F.SilkS" user "Ref Des/Silkscreen Top")
		(7 "B.SilkS" user "Ref Des/Silkscreen Bottom")
		(1 "F.Mask" user "Board Geometry/Soldermask Top")
		(3 "B.Mask" user "Board Geometry/Soldermask Bottom")
		(17 "Dwgs.User" user "User.Drawings")
		(19 "Cmts.User" user "User.Comments")
		(21 "Eco1.User" user "User.Eco1")
		(23 "Eco2.User" user "User.Eco2")
		(25 "Edge.Cuts" user "Board Geometry/Outline")
		(27 "Margin" user)
		(31 "F.CrtYd" user "Package Geometry/Place Bound Top")
		(29 "B.CrtYd" user "Package Geometry/Place Bound Bottom")
		(35 "F.Fab" user "Ref Des/Assembly Top")
		(33 "B.Fab" user "Ref Des/Assembly Bottom")
	)
	(footprint ""
		(layer "F.Cu")
		(at 262.7376 -230.3018 180)
		(property "Reference" "R96"
			(at 0 0 180)
			(layer "F.SilkS")
			(hide yes)
			(effects
				(font
					(size 1.27 1.27)
				)
			)
		)
		(property "Value" "4K7R2F-GP"
			(at 0.064008 -3.993896 180)
			(unlocked yes)
			(layer "F.Fab")
			(hide yes)
			(effects
				(font
					(size 1.016 1.016)
					(thickness 0.1524)
				)
			)
		)
		(property "Device Type" "R402H16"
			(at 0.064008 -5.517896 180)
			(unlocked yes)
			(layer "F.Fab")
			(hide yes)
			(effects
				(font
					(size 1.016 1.016)
					(thickness 0.1524)
				)
			)
		)
		(duplicate_pad_numbers_are_jumpers no)
		(fp_line
			(start 0.508 -0.9398)
			(end -0.508 -0.9398)
			(stroke
				(width 0.1524)
				(type default)
			)
			(layer "F.SilkS")
		)
		(fp_line
			(start -0.508 -0.9398)
			(end -0.508 0.9398)
			(stroke
				(width 0.1524)
				(type default)
			)
			(layer "F.SilkS")
		)
		(fp_rect
			(start -0.508 0.9398)
			(end 0.508 -0.9398)
			(stroke
				(width 0)
				(type default)
			)
			(fill no)
			(layer "F.CrtYd")
		)
		(fp_rect
			(start -0.508 0.9398)
			(end 0.508 -0.9398)
			(stroke
				(width 0)
				(type default)
			)
			(fill no)
			(layer "F.Fab")
		)
		(pad "1" smd custom
			(at 0 -0.4445 180)
			(size 0.1397 0.1397)
			(layers "F.Cu" "F.Mask" "F.Paste")
			(net "P3V3_STBY_A")
			(options
				(clearance outline)
				(anchor circle)
			)
			(primitives
				(gr_poly
					(pts
						(arc
							(start -0.1778 -0.2794)
							(mid -0.249642 -0.249642)
							(end -0.2794 -0.1778)
						)
						(arc
							(start -0.2794 0.1778)
							(mid -0.249642 0.249642)
							(end -0.1778 0.2794)
						)
						(arc
							(start 0.1778 0.2794)
							(mid 0.249642 0.249642)
							(end 0.2794 0.1778)
						)
						(arc
							(start 0.2794 -0.1778)
							(mid 0.249642 -0.249642)
							(end 0.1778 -0.2794)
						)
					)
					(width 0)
					(fill yes)
				)
			)
		)
		(pad "2" smd custom
			(at 0 0.4445 180)
			(size 0.1397 0.1397)
			(layers "F.Cu" "F.Mask" "F.Paste")
			(net "IO_EXP3_A0")
			(options
				(clearance outline)
				(anchor circle)
			)
			(primitives
				(gr_poly
					(pts
						(arc
							(start -0.1778 -0.2794)
							(mid -0.249642 -0.249642)
							(end -0.2794 -0.1778)
						)
						(arc
							(start -0.2794 0.1778)
							(mid -0.249642 0.249642)
							(end -0.1778 0.2794)
						)
						(arc
							(start 0.1778 0.2794)
							(mid 0.249642 0.249642)
							(end 0.2794 0.1778)
						)
						(arc
							(start 0.2794 -0.1778)
							(mid 0.249642 -0.249642)
							(end 0.1778 -0.2794)
						)
					)
					(width 0)
					(fill yes)
				)
			)
		)
	)
	(footprint ""
		(layer "F.Cu")
		(at 164.28212 -185.085482)
		(property "Reference" "Q268"
			(at 0 0 0)
			(layer "F.SilkS")
			(hide yes)
			(effects
				(font
					(size 1.27 1.27)
				)
			)
		)
		(property "Value" "SSM3K324R-GP"
			(at 0.127 -8.9662 0)
			(unlocked yes)
			(layer "F.Fab")
			(hide yes)
			(effects
				(font
					(size 1.016 1.016)
					(thickness 0.1524)
				)
			)
		)
		(property "Device Type" "SOT23DGS2D4H35"
			(at 0.127 -10.4902 0)
			(unlocked yes)
			(layer "F.Fab")
			(hide yes)
			(effects
				(font
					(size 1.016 1.016)
					(thickness 0.1524)
				)
			)
		)
		(duplicate_pad_numbers_are_jumpers no)
		(fp_line
			(start -1.651 -1.778)
			(end -1.651 1.778)
			(stroke
				(width 0.1524)
				(type default)
			)
			(layer "F.SilkS")
		)
		(fp_line
			(start -1.651 1.778)
			(end 1.651 1.778)
			(stroke
				(width 0.1524)
				(type default)
			)
			(layer "F.SilkS")
		)
		(fp_line
			(start 1.651 -1.778)
			(end -1.651 -1.778)
			(stroke
				(width 0.1524)
				(type default)
			)
			(layer "F.SilkS")
		)
		(fp_line
			(start 1.651 1.778)
			(end 1.651 -1.778)
			(stroke
				(width 0.1524)
				(type default)
			)
			(layer "F.SilkS")
		)
		(fp_poly
			(pts
				(xy -1.778 1.8796) (xy -1.778 -1.8796) (xy 1.778 -1.8796) (xy 1.778 1.8796)
			)
			(stroke
				(width 0)
				(type default)
			)
			(fill no)
			(layer "F.CrtYd")
		)
		(fp_poly
			(pts
				(xy -1.778 1.8796) (xy -1.778 -1.8796) (xy 1.778 -1.8796) (xy 1.778 1.8796)
			)
			(stroke
				(width 0)
				(type default)
			)
			(fill no)
			(layer "F.Fab")
		)
		(pad "D" smd custom
			(at 0 -0.9525)
			(size 0.1905 0.1905)
			(layers "F.Cu" "F.Mask" "F.Paste")
			(net "DRV_ACT_5_N")
			(options
				(clearance outline)
				(anchor circle)
			)
			(primitives
				(gr_poly
					(pts
						(arc
							(start -0.1778 0.5715)
							(mid -0.321484 0.511984)
							(end -0.381 0.3683)
						)
						(arc
							(start -0.381 -0.3683)
							(mid -0.321484 -0.511984)
							(end -0.1778 -0.5715)
						)
						(arc
							(start 0.1778 -0.5715)
							(mid 0.321484 -0.511984)
							(end 0.381 -0.3683)
						)
						(arc
							(start 0.381 0.3683)
							(mid 0.321484 0.511984)
							(end 0.1778 0.5715)
						)
					)
					(width 0)
					(fill yes)
				)
			)
		)
		(pad "G" smd custom
			(at -0.98425 0.9525)
			(size 0.1905 0.1905)
			(layers "F.Cu" "F.Mask" "F.Paste")
			(net "DRIVE_A_5_ACT")
			(options
				(clearance outline)
				(anchor circle)
			)
			(primitives
				(gr_poly
					(pts
						(arc
							(start -0.1778 0.5715)
							(mid -0.321484 0.511984)
							(end -0.381 0.3683)
						)
						(arc
							(start -0.381 -0.3683)
							(mid -0.321484 -0.511984)
							(end -0.1778 -0.5715)
						)
						(arc
							(start 0.1778 -0.5715)
							(mid 0.321484 -0.511984)
							(end 0.381 -0.3683)
						)
						(arc
							(start 0.381 0.3683)
							(mid 0.321484 0.511984)
							(end 0.1778 0.5715)
						)
					)
					(width 0)
					(fill yes)
				)
			)
		)
		(pad "S" smd custom
			(at 0.98425 0.9525)
			(size 0.1905 0.1905)
			(layers "F.Cu" "F.Mask" "F.Paste")
			(net "GND")
			(options
				(clearance outline)
				(anchor circle)
			)
			(primitives
				(gr_poly
					(pts
						(arc
							(start -0.1778 0.5715)
							(mid -0.321484 0.511984)
							(end -0.381 0.3683)
						)
						(arc
							(start -0.381 -0.3683)
							(mid -0.321484 -0.511984)
							(end -0.1778 -0.5715)
						)
						(arc
							(start 0.1778 -0.5715)
							(mid 0.321484 -0.511984)
							(end 0.381 -0.3683)
						)
						(arc
							(start 0.381 0.3683)
							(mid 0.321484 0.511984)
							(end 0.1778 0.5715)
						)
					)
					(width 0)
					(fill yes)
				)
			)
		)
	)
	(footprint ""
		(layer "F.Cu")
		(at 444.391542 -242.809522 180)
		(property "Reference" "Q273"
			(at 0 0 180)
			(layer "F.SilkS")
			(hide yes)
			(effects
				(font
					(size 1.27 1.27)
				)
			)
		)
		(property "Value" "SSM3K324R-GP"
			(at 0.127 -8.9662 180)
			(unlocked yes)
			(layer "F.Fab")
			(hide yes)
			(effects
				(font
					(size 1.016 1.016)
					(thickness 0.1524)
				)
			)
		)
		(property "Device Type" "SOT23DGS2D4H35"
			(at 0.127 -10.4902 180)
			(unlocked yes)
			(layer "F.Fab")
			(hide yes)
			(effects
				(font
					(size 1.016 1.016)
					(thickness 0.1524)
				)
			)
		)
		(duplicate_pad_numbers_are_jumpers no)
		(fp_line
			(start 1.651 1.778)
			(end 1.651 -1.778)
			(stroke
				(width 0.1524)
				(type default)
			)
			(layer "F.SilkS")
		)
		(fp_line
			(start 1.651 -1.778)
			(end -1.651 -1.778)
			(stroke
				(width 0.1524)
				(type default)
			)
			(layer "F.SilkS")
		)
		(fp_line
			(start -1.651 1.778)
			(end 1.651 1.778)
			(stroke
				(width 0.1524)
				(type default)
			)
			(layer "F.SilkS")
		)
		(fp_line
			(start -1.651 -1.778)
			(end -1.651 1.778)
			(stroke
				(width 0.1524)
				(type default)
			)
			(layer "F.SilkS")
		)
		(fp_poly
			(pts
				(xy -1.778 1.8796) (xy -1.778 -1.8796) (xy 1.778 -1.8796) (xy 1.778 1.8796)
			)
			(stroke
				(width 0)
				(type default)
			)
			(fill no)
			(layer "F.CrtYd")
		)
		(fp_poly
			(pts
				(xy -1.778 1.8796) (xy -1.778 -1.8796) (xy 1.778 -1.8796) (xy 1.778 1.8796)
			)
			(stroke
				(width 0)
				(type default)
			)
			(fill no)
			(layer "F.Fab")
		)
		(pad "D" smd custom
			(at 0 -0.9525 180)
			(size 0.1905 0.1905)
			(layers "F.Cu" "F.Mask" "F.Paste")
			(net "DRV_ACT_10_N")
			(options
				(clearance outline)
				(anchor circle)
			)
			(primitives
				(gr_poly
					(pts
						(arc
							(start -0.1778 0.5715)
							(mid -0.321484 0.511984)
							(end -0.381 0.3683)
						)
						(arc
							(start -0.381 -0.3683)
							(mid -0.321484 -0.511984)
							(end -0.1778 -0.5715)
						)
						(arc
							(start 0.1778 -0.5715)
							(mid 0.321484 -0.511984)
							(end 0.381 -0.3683)
						)
						(arc
							(start 0.381 0.3683)
							(mid 0.321484 0.511984)
							(end 0.1778 0.5715)
						)
					)
					(width 0)
					(fill yes)
				)
			)
		)
		(pad "G" smd custom
			(at -0.98425 0.9525 180)
			(size 0.1905 0.1905)
			(layers "F.Cu" "F.Mask" "F.Paste")
			(net "DRIVE_A_10_ACT")
			(options
				(clearance outline)
				(anchor circle)
			)
			(primitives
				(gr_poly
					(pts
						(arc
							(start -0.1778 0.5715)
							(mid -0.321484 0.511984)
							(end -0.381 0.3683)
						)
						(arc
							(start -0.381 -0.3683)
							(mid -0.321484 -0.511984)
							(end -0.1778 -0.5715)
						)
						(arc
							(start 0.1778 -0.5715)
							(mid 0.321484 -0.511984)
							(end 0.381 -0.3683)
						)
						(arc
							(start 0.381 0.3683)
							(mid 0.321484 0.511984)
							(end 0.1778 0.5715)
						)
					)
					(width 0)
					(fill yes)
				)
			)
		)
		(pad "S" smd custom
			(at 0.98425 0.9525 180)
			(size 0.1905 0.1905)
			(layers "F.Cu" "F.Mask" "F.Paste")
			(net "GND")
			(options
				(clearance outline)
				(anchor circle)
			)
			(primitives
				(gr_poly
					(pts
						(arc
							(start -0.1778 0.5715)
							(mid -0.321484 0.511984)
							(end -0.381 0.3683)
						)
						(arc
							(start -0.381 -0.3683)
							(mid -0.321484 -0.511984)
							(end -0.1778 -0.5715)
						)
						(arc
							(start 0.1778 -0.5715)
							(mid 0.321484 -0.511984)
							(end 0.381 -0.3683)
						)
						(arc
							(start 0.381 0.3683)
							(mid 0.321484 0.511984)
							(end 0.1778 0.5715)
						)
					)
					(width 0)
					(fill yes)
				)
			)
		)
	)
	(footprint ""
		(layer "F.Cu")
		(at 107.099862 -289.999928)
		(property "Reference" ""
			(at 0 0 0)
			(layer "F.SilkS")
			(hide yes)
			(effects
				(font
					(size 1.27 1.27)
				)
			)
		)
		(property "Value" "*"
			(at -6.3373 -0.4572 0)
			(unlocked yes)
			(layer "F.Fab")
			(hide yes)
			(effects
				(font
					(size 1.016 1.016)
					(thickness 0.1524)
				)
			)
		)
		(duplicate_pad_numbers_are_jumpers no)
		(fp_poly
			(pts
				(arc
					(start 5.0673 0)
					(mid -5.0673 0)
					(end 5.0673 0)
				)
			)
			(stroke
				(width 0)
				(type default)
			)
			(fill no)
			(layer "B.CrtYd")
		)
		(fp_poly
			(pts
				(arc
					(start 5.0673 0)
					(mid -5.0673 0)
					(end 5.0673 0)
				)
			)
			(stroke
				(width 0)
				(type default)
			)
			(fill no)
			(layer "F.CrtYd")
		)
		(fp_poly
			(pts
				(arc
					(start 5.0673 0)
					(mid -5.0673 0)
					(end 5.0673 0)
				)
			)
			(stroke
				(width 0)
				(type default)
			)
			(fill no)
			(layer "B.Fab")
		)
		(fp_poly
			(pts
				(arc
					(start 5.0673 0)
					(mid -5.0673 0)
					(end 5.0673 0)
				)
			)
			(stroke
				(width 0)
				(type default)
			)
			(fill no)
			(layer "F.Fab")
		)
		(pad "1" thru_hole circle
			(at 0 0)
			(size 9.525 9.525)
			(drill 3.556)
			(layers "*.Cu" "*.Mask")
			(remove_unused_layers no)
			(net "Net_91")
			(clearance -2.4765)
			(thermal_gap 0.3048)
			(padstack
				(mode front_inner_back)
				(layer "Inner"
					(shape circle)
					(size 3.9624 3.9624)
					(clearance 0.3048)
				)
				(layer "B.Cu"
					(shape circle)
					(size 9.525 9.525)
					(clearance -2.4765)
				)
			)
		)
		(zone
			(layers "F.Cu" "B.Cu" "In1.Cu" "In2.Cu" "In3.Cu" "In4.Cu" "In5.Cu" "In6.Cu"
				"In7.Cu" "In8.Cu" "In9.Cu" "In10.Cu"
			)
			(hatch none 0.5)
			(connect_pads
				(clearance 0)
			)
			(min_thickness 0.25)
			(keepout
				(tracks not_allowed)
				(vias allowed)
				(pads allowed)
				(copperpour not_allowed)
				(footprints allowed)
			)
			(placement
				(enabled no)
				(sheetname "")
			)
			(fill
				(thermal_gap 0.5)
				(thermal_bridge_width 0.5)
				(island_removal_mode 0)
			)
			(polygon
				(pts
					(arc
						(start 111.862362 -289.999928)
						(mid 102.337362 -289.999928)
						(end 111.862362 -289.999928)
					)
				)
			)
		)
	)
	(footprint ""
		(layer "F.Cu")
		(at 98.823018 -296.67962)
		(property "Reference" "R562"
			(at 0 0 0)
			(layer "F.SilkS")
			(hide yes)
			(effects
				(font
					(size 1.27 1.27)
				)
			)
		)
		(property "Value" "4K7R2J-2-GP"
			(at 0.064008 -3.993896 0)
			(unlocked yes)
			(layer "F.Fab")
			(hide yes)
			(effects
				(font
					(size 1.016 1.016)
					(thickness 0.1524)
				)
			)
		)
		(property "Device Type" "R402H16"
			(at 0.064008 -5.517896 0)
			(unlocked yes)
			(layer "F.Fab")
			(hide yes)
			(effects
				(font
					(size 1.016 1.016)
					(thickness 0.1524)
				)
			)
		)
		(duplicate_pad_numbers_are_jumpers no)
		(fp_line
			(start -0.508 -0.9398)
			(end -0.508 0.9398)
			(stroke
				(width 0.1524)
				(type default)
			)
			(layer "F.SilkS")
		)
		(fp_line
			(start 0.508 -0.9398)
			(end -0.508 -0.9398)
			(stroke
				(width 0.1524)
				(type default)
			)
			(layer "F.SilkS")
		)
		(fp_rect
			(start -0.508 0.9398)
			(end 0.508 -0.9398)
			(stroke
				(width 0)
				(type default)
			)
			(fill no)
			(layer "F.CrtYd")
		)
		(fp_rect
			(start -0.508 0.9398)
			(end 0.508 -0.9398)
			(stroke
				(width 0)
				(type default)
			)
			(fill no)
			(layer "F.Fab")
		)
		(pad "1" smd custom
			(at 0 -0.4445)
			(size 0.1397 0.1397)
			(layers "F.Cu" "F.Mask" "F.Paste")
			(net "DRIVE_B_27_ACT")
			(options
				(clearance outline)
				(anchor circle)
			)
			(primitives
				(gr_poly
					(pts
						(arc
							(start -0.1778 -0.2794)
							(mid -0.249642 -0.249642)
							(end -0.2794 -0.1778)
						)
						(arc
							(start -0.2794 0.1778)
							(mid -0.249642 0.249642)
							(end -0.1778 0.2794)
						)
						(arc
							(start 0.1778 0.2794)
							(mid 0.249642 0.249642)
							(end 0.2794 0.1778)
						)
						(arc
							(start 0.2794 -0.1778)
							(mid 0.249642 -0.249642)
							(end 0.1778 -0.2794)
						)
					)
					(width 0)
					(fill yes)
				)
			)
		)
		(pad "2" smd custom
			(at 0 0.4445)
			(size 0.1397 0.1397)
			(layers "F.Cu" "F.Mask" "F.Paste")
			(net "GND")
			(options
				(clearance outline)
				(anchor circle)
			)
			(primitives
				(gr_poly
					(pts
						(arc
							(start -0.1778 -0.2794)
							(mid -0.249642 -0.249642)
							(end -0.2794 -0.1778)
						)
						(arc
							(start -0.2794 0.1778)
							(mid -0.249642 0.249642)
							(end -0.1778 0.2794)
						)
						(arc
							(start 0.1778 0.2794)
							(mid 0.249642 0.249642)
							(end 0.2794 0.1778)
						)
						(arc
							(start 0.2794 -0.1778)
							(mid 0.249642 -0.249642)
							(end 0.1778 -0.2794)
						)
					)
					(width 0)
					(fill yes)
				)
			)
		)
	)
)
